#ISCELL
  pure_quanta quanta_title_block_c *
  *
#CELL
  pure_quanta pt5161lrs *
  page394_i1
#ISCELL
  standard tap *
  page394_i10
#ISCELL
  standard tap *
  page394_i11
#ISCELL
  standard tap *
  page394_i12
#ISCELL
  standard tap *
  page394_i13
#ISCELL
  standard tap *
  page394_i14
#ISCELL
  standard tap *
  page394_i15
#ISCELL
  standard tap *
  page394_i16
#ISCELL
  standard tap *
  page394_i17
#ISCELL
  standard offpage *
  page394_i18
#ISCELL
  standard offpage *
  page394_i19
#ISCELL
  standard tap *
  page394_i2
#ISCELL
  standard tap *
  page394_i20
#ISCELL
  standard tap *
  page394_i21
#ISCELL
  standard tap *
  page394_i22
#ISCELL
  standard tap *
  page394_i23
#ISCELL
  standard tap *
  page394_i24
#ISCELL
  standard tap *
  page394_i25
#ISCELL
  standard tap *
  page394_i26
#ISCELL
  standard tap *
  page394_i27
#ISCELL
  standard tap *
  page394_i28
#ISCELL
  standard tap *
  page394_i29
#ISCELL
  standard tap *
  page394_i3
#ISCELL
  standard tap *
  page394_i30
#ISCELL
  standard tap *
  page394_i31
#ISCELL
  standard tap *
  page394_i32
#ISCELL
  standard tap *
  page394_i33
#ISCELL
  standard tap *
  page394_i34
#ISCELL
  standard tap *
  page394_i35
#ISCELL
  standard offpage *
  page394_i36
#ISCELL
  standard offpage *
  page394_i37
#CELL
  pure_quanta pt5161lrs *
  page394_i38
#ISCELL
  standard tap *
  page394_i4
#ISCELL
  standard tap *
  page394_i5
#ISCELL
  standard tap *
  page394_i6
#ISCELL
  standard tap *
  page394_i7
#ISCELL
  standard tap *
  page394_i8
#ISCELL
  standard tap *
  page394_i9
